FILE_TYPE = MULTI_PHYS_TABLE;

PART 'RT9818C44GV'

{========================================================================================}
:VALUE          | PART_TYPE | MATERIAL | PART_NUMBER    = STANDARD | LIFECYCLE     | PART_NUMBER   | JEDEC_TYPE           | DESCRIPTION                         | MANUFTR | MANUF_PN       | RD_CMPLS_LVL | CMPLS_LVL | FROM_PJ      | CLASS | DIP_SMD | DATA                   | EE_CHECK_LIST | FP_ECN | PSL | CREATOR | STATUS | CREATEDAY  ;
{========================================================================================}
 'RT9818C-44GV' | 'SMLF'    | 'IC'     | 'AL009818001'(!) = ''       | ''               | 'AL009818001' |'SOT23_123_2-89X1-6'| 'IC OTHER(3P)RT9818C-44GV(SOT23-3)' | 'RTK'   | 'RT9818C-44GV' | 'EP(V1)'     | ''        | 'S5B-YU-LIN' | 'IC'  | ''      | 'RTK_RT9818C-44GV.pdf' | ''            | ''     | ''  | ''      | ''     | '20150914'
 'RT9818C-44GV' | 'SMLF'    | 'EMPTY'  | 'AL009818001'(!) = ''       | ''               | 'AL009818001' |'SOT23_123_2-89X1-6'| 'IC OTHER(3P)RT9818C-44GV(SOT23-3)' | 'RTK'   | 'RT9818C-44GV' | 'EP(V1)'     | ''        | 'S5B-YU-LIN' | 'IC'  | ''      | 'RTK_RT9818C-44GV.pdf' | ''            | ''     | ''  | ''      | ''     | '20150914'

END_PART

END.

